(kicad_pcb
	(version 20260206)
	(generator "pcbnew")
	(generator_version "10.0")
	(general
		(thickness 1.6)
		(legacy_teardrops no)
	)
	(paper "A4")
	(title_block
		(title "01162023_DA0F0TEBIF0_F0T_Expander_BD_F_brd_V02_OCP.brd")
		(comment 1 "Grand Teton / footprints 9383-9391 of 9728")
	)
	(layers
		(0 "F.Cu" signal "TOP")
		(4 "In1.Cu" signal "GND")
		(6 "In2.Cu" signal "VCC")
		(8 "In3.Cu" signal "VCC1")
		(10 "In4.Cu" signal "GND1")
		(12 "In5.Cu" signal "IN1")
		(14 "In6.Cu" signal "GND2")
		(16 "In7.Cu" signal "IN2")
		(18 "In8.Cu" signal "GND3")
		(20 "In9.Cu" signal "IN3")
		(22 "In10.Cu" signal "GND4")
		(24 "In11.Cu" signal "IN4")
		(26 "In12.Cu" signal "GND5")
		(28 "In13.Cu" signal "IN5")
		(30 "In14.Cu" signal "GND6")
		(32 "In15.Cu" signal "IN6")
		(34 "In16.Cu" signal "GND7")
		(2 "B.Cu" signal "BOTTOM")
		(9 "F.Adhes" user "F.Adhesive")
		(11 "B.Adhes" user "B.Adhesive")
		(13 "F.Paste" user "Package Geometry/Pastemask Top")
		(15 "B.Paste" user "Package Geometry/Pastemask Bottom")
		(5 "F.SilkS" user "Ref Des/Silkscreen Top")
		(7 "B.SilkS" user "Ref Des/Silkscreen Bottom")
		(1 "F.Mask" user "Board Geometry/Soldermask Top")
		(3 "B.Mask" user "Board Geometry/Soldermask Bottom")
		(17 "Dwgs.User" user "User.Drawings")
		(19 "Cmts.User" user "User.Comments")
		(21 "Eco1.User" user "User.Eco1")
		(23 "Eco2.User" user "User.Eco2")
		(25 "Edge.Cuts" user "Board Geometry/Outline")
		(27 "Margin" user)
		(31 "F.CrtYd" user "Package Geometry/Place Bound Top")
		(29 "B.CrtYd" user "Package Geometry/Place Bound Bottom")
		(35 "F.Fab" user "Ref Des/Assembly Top")
		(33 "B.Fab" user "Ref Des/Assembly Bottom")
	)
	(footprint ""
		(layer "B.Cu")
		(at 122.689366 -313.620404)
		(property "Reference" "L27"
			(at 0 0 0)
			(layer "B.SilkS")
			(hide yes)
			(effects
				(font
					(size 1.27 1.27)
				)
				(justify mirror)
			)
		)
		(property "Value" ""
			(at 0 0 0)
			(layer "B.Fab")
			(effects
				(font
					(size 1.27 1.27)
				)
				(justify mirror)
			)
		)
		(duplicate_pad_numbers_are_jumpers no)
		(fp_line
			(start -2.248154 -4.9911)
			(end 2.248154 -4.9911)
			(stroke
				(width 0.1524)
				(type default)
			)
			(layer "B.SilkS")
		)
		(fp_line
			(start -2.248154 -1.794764)
			(end -2.248154 -4.9911)
			(stroke
				(width 0.1524)
				(type default)
			)
			(layer "B.SilkS")
		)
		(fp_line
			(start -2.248154 4.9911)
			(end -2.248154 2.100834)
			(stroke
				(width 0.1524)
				(type default)
			)
			(layer "B.SilkS")
		)
		(fp_line
			(start 2.248154 -4.9911)
			(end 2.248154 -1.794764)
			(stroke
				(width 0.1524)
				(type default)
			)
			(layer "B.SilkS")
		)
		(fp_line
			(start 2.248154 2.100834)
			(end 2.248154 4.9911)
			(stroke
				(width 0.1524)
				(type default)
			)
			(layer "B.SilkS")
		)
		(fp_line
			(start 2.248154 4.9911)
			(end -2.248154 4.9911)
			(stroke
				(width 0.1524)
				(type default)
			)
			(layer "B.SilkS")
		)
		(fp_line
			(start -1.700022 -0.899922)
			(end 1.700022 -0.899922)
			(stroke
				(width 0.1)
				(type default)
			)
			(layer "B.Fab")
		)
		(fp_line
			(start -1.700022 0.899922)
			(end -1.700022 -0.899922)
			(stroke
				(width 0.1)
				(type default)
			)
			(layer "B.Fab")
		)
		(fp_line
			(start 1.700022 -0.899922)
			(end 1.700022 0.899922)
			(stroke
				(width 0.1)
				(type default)
			)
			(layer "B.Fab")
		)
		(fp_line
			(start 1.700022 0.899922)
			(end -1.700022 0.899922)
			(stroke
				(width 0.1)
				(type default)
			)
			(layer "B.Fab")
		)
		(pad "1" smd rect
			(at 1.575054 0 180)
			(size 1.1684 9.8044)
			(layers "B.Cu" "B.Mask" "B.Paste")
			(net "P0V8_PEX1")
		)
		(pad "2" smd rect
			(at -1.575054 0 180)
			(size 1.1684 9.8044)
			(layers "B.Cu" "B.Mask" "B.Paste")
			(net "P0V8_SERDES_VDDA_PEX1")
		)
	)
	(footprint ""
		(layer "B.Cu")
		(at 135.387842 -182.052468 90)
		(property "Reference" "R1123"
			(at 0 0 90)
			(layer "B.SilkS")
			(hide yes)
			(effects
				(font
					(size 1.27 1.27)
				)
				(justify mirror)
			)
		)
		(property "Value" ""
			(at 0 0 90)
			(layer "B.Fab")
			(effects
				(font
					(size 1.27 1.27)
				)
				(justify mirror)
			)
		)
		(duplicate_pad_numbers_are_jumpers no)
		(fp_line
			(start 0.7874 -0.4064)
			(end -0.7874 -0.4064)
			(stroke
				(width 0.1524)
				(type default)
			)
			(layer "B.SilkS")
		)
		(fp_line
			(start -0.7874 -0.4064)
			(end -0.7874 0.4064)
			(stroke
				(width 0.1524)
				(type default)
			)
			(layer "B.SilkS")
		)
		(fp_line
			(start 0.7874 0.4064)
			(end 0.7874 -0.4064)
			(stroke
				(width 0.1524)
				(type default)
			)
			(layer "B.SilkS")
		)
		(fp_line
			(start -0.7874 0.4064)
			(end 0.7874 0.4064)
			(stroke
				(width 0.1524)
				(type default)
			)
			(layer "B.SilkS")
		)
		(fp_line
			(start 0.67945 -0.305054)
			(end 0.12065 -0.305054)
			(stroke
				(width 0.1)
				(type default)
			)
			(layer "B.Fab")
		)
		(fp_line
			(start 0.12065 -0.305054)
			(end 0.12065 -0.2794)
			(stroke
				(width 0.1)
				(type default)
			)
			(layer "B.Fab")
		)
		(fp_line
			(start -0.12065 -0.3048)
			(end -0.67945 -0.3048)
			(stroke
				(width 0.1)
				(type default)
			)
			(layer "B.Fab")
		)
		(fp_line
			(start -0.67945 -0.3048)
			(end -0.67945 0.3048)
			(stroke
				(width 0.1)
				(type default)
			)
			(layer "B.Fab")
		)
		(fp_line
			(start 0.12065 -0.2794)
			(end -0.12065 -0.2794)
			(stroke
				(width 0.1)
				(type default)
			)
			(layer "B.Fab")
		)
		(fp_line
			(start -0.12065 -0.2794)
			(end -0.12065 -0.3048)
			(stroke
				(width 0.1)
				(type default)
			)
			(layer "B.Fab")
		)
		(fp_line
			(start 0.12065 0.2794)
			(end 0.12065 0.3048)
			(stroke
				(width 0.1)
				(type default)
			)
			(layer "B.Fab")
		)
		(fp_line
			(start -0.120396 0.2794)
			(end 0.12065 0.2794)
			(stroke
				(width 0.1)
				(type default)
			)
			(layer "B.Fab")
		)
		(fp_line
			(start 0.67945 0.3048)
			(end 0.67945 -0.305054)
			(stroke
				(width 0.1)
				(type default)
			)
			(layer "B.Fab")
		)
		(fp_line
			(start 0.12065 0.3048)
			(end 0.67945 0.3048)
			(stroke
				(width 0.1)
				(type default)
			)
			(layer "B.Fab")
		)
		(fp_line
			(start -0.120396 0.3048)
			(end -0.120396 0.2794)
			(stroke
				(width 0.1)
				(type default)
			)
			(layer "B.Fab")
		)
		(fp_line
			(start -0.67945 0.3048)
			(end -0.120396 0.3048)
			(stroke
				(width 0.1)
				(type default)
			)
			(layer "B.Fab")
		)
		(pad "1" smd circle
			(at 0.40005 0 270)
			(size 0 0)
			(layers "B.Cu" "B.Mask" "B.Paste")
			(net "GND")
		)
		(pad "2" smd circle
			(at -0.40005 0 270)
			(size 0 0)
			(layers "B.Cu" "B.Mask" "B.Paste")
			(net "FM_DB2000QL_SMB_SA1")
		)
	)
	(footprint ""
		(layer "B.Cu")
		(at 162.455098 -300.1772)
		(property "Reference" "C3199"
			(at 0 0 0)
			(layer "B.SilkS")
			(hide yes)
			(effects
				(font
					(size 1.27 1.27)
				)
				(justify mirror)
			)
		)
		(property "Value" ""
			(at 0 0 0)
			(layer "B.Fab")
			(effects
				(font
					(size 1.27 1.27)
				)
				(justify mirror)
			)
		)
		(duplicate_pad_numbers_are_jumpers no)
		(fp_line
			(start -0.299974 -0.150114)
			(end -0.299974 0.150114)
			(stroke
				(width 0.1)
				(type default)
			)
			(layer "B.Fab")
		)
		(fp_line
			(start -0.299974 0.150114)
			(end 0.299974 0.150114)
			(stroke
				(width 0.1)
				(type default)
			)
			(layer "B.Fab")
		)
		(fp_line
			(start 0.299974 -0.150114)
			(end -0.299974 -0.150114)
			(stroke
				(width 0.1)
				(type default)
			)
			(layer "B.Fab")
		)
		(fp_line
			(start 0.299974 0.150114)
			(end 0.299974 -0.150114)
			(stroke
				(width 0.1)
				(type default)
			)
			(layer "B.Fab")
		)
		(pad "1" smd rect
			(at 0.2667 0 180)
			(size 0.3048 0.381)
			(layers "B.Cu" "B.Mask" "B.Paste")
			(net "PCEPLL1_VDDA18_PEX1")
		)
		(pad "2" smd rect
			(at -0.2667 0 180)
			(size 0.3048 0.381)
			(layers "B.Cu" "B.Mask" "B.Paste")
			(net "GND")
		)
	)
	(footprint ""
		(layer "B.Cu")
		(at 301.607474 -221.694502 -90)
		(property "Reference" "R1860"
			(at 0 0 90)
			(layer "B.SilkS")
			(hide yes)
			(effects
				(font
					(size 1.27 1.27)
				)
				(justify mirror)
			)
		)
		(property "Value" ""
			(at 0 0 90)
			(layer "B.Fab")
			(effects
				(font
					(size 1.27 1.27)
				)
				(justify mirror)
			)
		)
		(duplicate_pad_numbers_are_jumpers no)
		(fp_line
			(start -0.7874 0.4064)
			(end 0.7874 0.4064)
			(stroke
				(width 0.1524)
				(type default)
			)
			(layer "B.SilkS")
		)
		(fp_line
			(start 0.7874 0.4064)
			(end 0.7874 -0.4064)
			(stroke
				(width 0.1524)
				(type default)
			)
			(layer "B.SilkS")
		)
		(fp_line
			(start -0.7874 -0.4064)
			(end -0.7874 0.4064)
			(stroke
				(width 0.1524)
				(type default)
			)
			(layer "B.SilkS")
		)
		(fp_line
			(start 0.7874 -0.4064)
			(end -0.7874 -0.4064)
			(stroke
				(width 0.1524)
				(type default)
			)
			(layer "B.SilkS")
		)
		(fp_line
			(start -0.67945 0.3048)
			(end -0.120396 0.3048)
			(stroke
				(width 0.1)
				(type default)
			)
			(layer "B.Fab")
		)
		(fp_line
			(start -0.120396 0.3048)
			(end -0.120396 0.2794)
			(stroke
				(width 0.1)
				(type default)
			)
			(layer "B.Fab")
		)
		(fp_line
			(start 0.12065 0.3048)
			(end 0.67945 0.3048)
			(stroke
				(width 0.1)
				(type default)
			)
			(layer "B.Fab")
		)
		(fp_line
			(start 0.67945 0.3048)
			(end 0.67945 -0.305054)
			(stroke
				(width 0.1)
				(type default)
			)
			(layer "B.Fab")
		)
		(fp_line
			(start -0.120396 0.2794)
			(end 0.12065 0.2794)
			(stroke
				(width 0.1)
				(type default)
			)
			(layer "B.Fab")
		)
		(fp_line
			(start 0.12065 0.2794)
			(end 0.12065 0.3048)
			(stroke
				(width 0.1)
				(type default)
			)
			(layer "B.Fab")
		)
		(fp_line
			(start -0.12065 -0.2794)
			(end -0.12065 -0.3048)
			(stroke
				(width 0.1)
				(type default)
			)
			(layer "B.Fab")
		)
		(fp_line
			(start 0.12065 -0.2794)
			(end -0.12065 -0.2794)
			(stroke
				(width 0.1)
				(type default)
			)
			(layer "B.Fab")
		)
		(fp_line
			(start -0.67945 -0.3048)
			(end -0.67945 0.3048)
			(stroke
				(width 0.1)
				(type default)
			)
			(layer "B.Fab")
		)
		(fp_line
			(start -0.12065 -0.3048)
			(end -0.67945 -0.3048)
			(stroke
				(width 0.1)
				(type default)
			)
			(layer "B.Fab")
		)
		(fp_line
			(start 0.12065 -0.305054)
			(end 0.12065 -0.2794)
			(stroke
				(width 0.1)
				(type default)
			)
			(layer "B.Fab")
		)
		(fp_line
			(start 0.67945 -0.305054)
			(end 0.12065 -0.305054)
			(stroke
				(width 0.1)
				(type default)
			)
			(layer "B.Fab")
		)
		(pad "1" smd circle
			(at 0.40005 0 90)
			(size 0 0)
			(layers "B.Cu" "B.Mask" "B.Paste")
			(net "P3V3_AUX")
		)
		(pad "2" smd circle
			(at -0.40005 0 90)
			(size 0 0)
			(layers "B.Cu" "B.Mask" "B.Paste")
			(net "RST_GPU_PERST_2_N")
		)
	)
	(footprint ""
		(layer "B.Cu")
		(at 69.624956 -304.241454 90)
		(property "Reference" "C3014"
			(at 0 0 90)
			(layer "B.SilkS")
			(hide yes)
			(effects
				(font
					(size 1.27 1.27)
				)
				(justify mirror)
			)
		)
		(property "Value" ""
			(at 0 0 90)
			(layer "B.Fab")
			(effects
				(font
					(size 1.27 1.27)
				)
				(justify mirror)
			)
		)
		(duplicate_pad_numbers_are_jumpers no)
		(fp_line
			(start 0.299974 -0.150114)
			(end -0.299974 -0.150114)
			(stroke
				(width 0.1)
				(type default)
			)
			(layer "B.Fab")
		)
		(fp_line
			(start -0.299974 -0.150114)
			(end -0.299974 0.150114)
			(stroke
				(width 0.1)
				(type default)
			)
			(layer "B.Fab")
		)
		(fp_line
			(start 0.299974 0.150114)
			(end 0.299974 -0.150114)
			(stroke
				(width 0.1)
				(type default)
			)
			(layer "B.Fab")
		)
		(fp_line
			(start -0.299974 0.150114)
			(end 0.299974 0.150114)
			(stroke
				(width 0.1)
				(type default)
			)
			(layer "B.Fab")
		)
		(pad "1" smd rect
			(at 0.2667 0 270)
			(size 0.3048 0.381)
			(layers "B.Cu" "B.Mask" "B.Paste")
			(net "P1V8_VDDA_PEX0")
		)
		(pad "2" smd rect
			(at -0.2667 0 270)
			(size 0.3048 0.381)
			(layers "B.Cu" "B.Mask" "B.Paste")
			(net "GND")
		)
	)
	(footprint ""
		(layer "B.Cu")
		(at 217.705686 -272.617438)
		(property "Reference" "C4288"
			(at 0 0 0)
			(layer "B.SilkS")
			(hide yes)
			(effects
				(font
					(size 1.27 1.27)
				)
				(justify mirror)
			)
		)
		(property "Value" ""
			(at 0 0 0)
			(layer "B.Fab")
			(effects
				(font
					(size 1.27 1.27)
				)
				(justify mirror)
			)
		)
		(duplicate_pad_numbers_are_jumpers no)
		(fp_line
			(start -1.2954 -0.5842)
			(end -1.2954 0.5842)
			(stroke
				(width 0.1524)
				(type default)
			)
			(layer "B.SilkS")
		)
		(fp_line
			(start -1.2954 0.5842)
			(end 1.2954 0.5842)
			(stroke
				(width 0.1524)
				(type default)
			)
			(layer "B.SilkS")
		)
		(fp_line
			(start 1.2954 -0.5842)
			(end -1.2954 -0.5842)
			(stroke
				(width 0.1524)
				(type default)
			)
			(layer "B.SilkS")
		)
		(fp_line
			(start 1.2954 0.5842)
			(end 1.2954 -0.5842)
			(stroke
				(width 0.1524)
				(type default)
			)
			(layer "B.SilkS")
		)
		(fp_line
			(start -1.1938 -0.4064)
			(end -1.1938 0.4064)
			(stroke
				(width 0.1)
				(type default)
			)
			(layer "B.Fab")
		)
		(fp_line
			(start -1.1938 0.4064)
			(end -0.8636 0.4064)
			(stroke
				(width 0.1)
				(type default)
			)
			(layer "B.Fab")
		)
		(fp_line
			(start -0.8636 -0.4572)
			(end -0.8636 -0.4064)
			(stroke
				(width 0.1)
				(type default)
			)
			(layer "B.Fab")
		)
		(fp_line
			(start -0.8636 -0.4064)
			(end -1.1938 -0.4064)
			(stroke
				(width 0.1)
				(type default)
			)
			(layer "B.Fab")
		)
		(fp_line
			(start -0.8636 0.4064)
			(end -0.8636 0.4572)
			(stroke
				(width 0.1)
				(type default)
			)
			(layer "B.Fab")
		)
		(fp_line
			(start -0.8636 0.4572)
			(end 0.8636 0.4572)
			(stroke
				(width 0.1)
				(type default)
			)
			(layer "B.Fab")
		)
		(fp_line
			(start 0.8636 -0.4572)
			(end -0.8636 -0.4572)
			(stroke
				(width 0.1)
				(type default)
			)
			(layer "B.Fab")
		)
		(fp_line
			(start 0.8636 -0.4064)
			(end 0.8636 -0.4572)
			(stroke
				(width 0.1)
				(type default)
			)
			(layer "B.Fab")
		)
		(fp_line
			(start 0.8636 0.4064)
			(end 1.1938 0.4064)
			(stroke
				(width 0.1)
				(type default)
			)
			(layer "B.Fab")
		)
		(fp_line
			(start 0.8636 0.4572)
			(end 0.8636 0.4064)
			(stroke
				(width 0.1)
				(type default)
			)
			(layer "B.Fab")
		)
		(fp_line
			(start 1.1938 -0.4064)
			(end 0.8636 -0.4064)
			(stroke
				(width 0.1)
				(type default)
			)
			(layer "B.Fab")
		)
		(fp_line
			(start 1.1938 0.4064)
			(end 1.1938 -0.4064)
			(stroke
				(width 0.1)
				(type default)
			)
			(layer "B.Fab")
		)
		(pad "1" smd rect
			(at 0.7366 0 270)
			(size 0.7112 0.8128)
			(layers "B.Cu" "B.Mask" "B.Paste")
			(net "P1V25_PEX1")
		)
		(pad "2" smd rect
			(at -0.7366 0 270)
			(size 0.7112 0.8128)
			(layers "B.Cu" "B.Mask" "B.Paste")
			(net "GND")
		)
	)
	(footprint ""
		(layer "B.Cu")
		(at 68.408042 -299.224954 180)
		(property "Reference" "C1164"
			(at 0 0 0)
			(layer "B.SilkS")
			(hide yes)
			(effects
				(font
					(size 1.27 1.27)
				)
				(justify mirror)
			)
		)
		(property "Value" ""
			(at 0 0 0)
			(layer "B.Fab")
			(effects
				(font
					(size 1.27 1.27)
				)
				(justify mirror)
			)
		)
		(duplicate_pad_numbers_are_jumpers no)
		(fp_line
			(start 0.299974 0.150114)
			(end 0.299974 -0.150114)
			(stroke
				(width 0.1)
				(type default)
			)
			(layer "B.Fab")
		)
		(fp_line
			(start 0.299974 -0.150114)
			(end -0.299974 -0.150114)
			(stroke
				(width 0.1)
				(type default)
			)
			(layer "B.Fab")
		)
		(fp_line
			(start -0.299974 0.150114)
			(end 0.299974 0.150114)
			(stroke
				(width 0.1)
				(type default)
			)
			(layer "B.Fab")
		)
		(fp_line
			(start -0.299974 -0.150114)
			(end -0.299974 0.150114)
			(stroke
				(width 0.1)
				(type default)
			)
			(layer "B.Fab")
		)
		(pad "1" smd rect
			(at 0.2667 0)
			(size 0.3048 0.381)
			(layers "B.Cu" "B.Mask" "B.Paste")
			(net "P0V8_SERDES_VDDA_PEX0")
		)
		(pad "2" smd rect
			(at -0.2667 0)
			(size 0.3048 0.381)
			(layers "B.Cu" "B.Mask" "B.Paste")
			(net "GND")
		)
	)
	(footprint ""
		(layer "B.Cu")
		(at 46.355 -300.1772)
		(property "Reference" "C3025"
			(at 0 0 0)
			(layer "B.SilkS")
			(hide yes)
			(effects
				(font
					(size 1.27 1.27)
				)
				(justify mirror)
			)
		)
		(property "Value" ""
			(at 0 0 0)
			(layer "B.Fab")
			(effects
				(font
					(size 1.27 1.27)
				)
				(justify mirror)
			)
		)
		(duplicate_pad_numbers_are_jumpers no)
		(fp_line
			(start -0.299974 -0.150114)
			(end -0.299974 0.150114)
			(stroke
				(width 0.1)
				(type default)
			)
			(layer "B.Fab")
		)
		(fp_line
			(start -0.299974 0.150114)
			(end 0.299974 0.150114)
			(stroke
				(width 0.1)
				(type default)
			)
			(layer "B.Fab")
		)
		(fp_line
			(start 0.299974 -0.150114)
			(end -0.299974 -0.150114)
			(stroke
				(width 0.1)
				(type default)
			)
			(layer "B.Fab")
		)
		(fp_line
			(start 0.299974 0.150114)
			(end 0.299974 -0.150114)
			(stroke
				(width 0.1)
				(type default)
			)
			(layer "B.Fab")
		)
		(pad "1" smd rect
			(at 0.2667 0 180)
			(size 0.3048 0.381)
			(layers "B.Cu" "B.Mask" "B.Paste")
			(net "PCEPLL1_VDDA18_PEX0")
		)
		(pad "2" smd rect
			(at -0.2667 0 180)
			(size 0.3048 0.381)
			(layers "B.Cu" "B.Mask" "B.Paste")
			(net "GND")
		)
	)
	(footprint ""
		(layer "B.Cu")
		(at 460.169006 -291.823648 180)
		(property "Reference" "PC999"
			(at 0 0 0)
			(layer "B.SilkS")
			(hide yes)
			(effects
				(font
					(size 1.27 1.27)
				)
				(justify mirror)
			)
		)
		(property "Value" ""
			(at 0 0 0)
			(layer "B.Fab")
			(effects
				(font
					(size 1.27 1.27)
				)
				(justify mirror)
			)
		)
		(duplicate_pad_numbers_are_jumpers no)
		(fp_line
			(start 1.524 0.762)
			(end 1.524 -0.762)
			(stroke
				(width 0.1524)
				(type default)
			)
			(layer "B.SilkS")
		)
		(fp_line
			(start 1.524 -0.762)
			(end -1.524 -0.762)
			(stroke
				(width 0.1524)
				(type default)
			)
			(layer "B.SilkS")
		)
		(fp_line
			(start -1.524 0.762)
			(end 1.524 0.762)
			(stroke
				(width 0.1524)
				(type default)
			)
			(layer "B.SilkS")
		)
		(fp_line
			(start -1.524 -0.762)
			(end -1.524 0.762)
			(stroke
				(width 0.1524)
				(type default)
			)
			(layer "B.SilkS")
		)
		(fp_line
			(start 1.1049 0.724916)
			(end -1.1049 0.724916)
			(stroke
				(width 0.1)
				(type default)
			)
			(layer "B.Fab")
		)
		(fp_line
			(start 1.1049 -0.724916)
			(end 1.1049 0.724916)
			(stroke
				(width 0.1)
				(type default)
			)
			(layer "B.Fab")
		)
		(fp_line
			(start -1.1049 0.724916)
			(end -1.1049 -0.724916)
			(stroke
				(width 0.1)
				(type default)
			)
			(layer "B.Fab")
		)
		(fp_line
			(start -1.1049 -0.724916)
			(end 1.1049 -0.724916)
			(stroke
				(width 0.1)
				(type default)
			)
			(layer "B.Fab")
		)
		(pad "1" smd rect
			(at 0.889 0 180)
			(size 1.016 1.27)
			(layers "B.Cu" "B.Mask" "B.Paste")
			(net "P1V25_PEX3_R")
		)
		(pad "2" smd rect
			(at -0.889 0 180)
			(size 1.016 1.27)
			(layers "B.Cu" "B.Mask" "B.Paste")
			(net "GND")
		)
	)
)
